(kicad_pcb
	(version 20260206)
	(generator "pcbnew")
	(generator_version "10.0")
	(general
		(thickness 1.6)
		(legacy_teardrops no)
	)
	(paper "A4")
	(title_block
		(title "Wiwynn_Tioga_Pass_MB.brd")
		(comment 1 "Tioga Pass / footprints 4454-4460 of 4770")
	)
	(layers
		(0 "F.Cu" signal "TOP")
		(4 "In1.Cu" signal "L2GND")
		(6 "In2.Cu" signal "L3")
		(8 "In3.Cu" signal "L4GND")
		(10 "In4.Cu" signal "L5")
		(12 "In5.Cu" signal "L6GND")
		(14 "In6.Cu" signal "L7VCC")
		(16 "In7.Cu" signal "L8VCC")
		(18 "In8.Cu" signal "L9GND")
		(20 "In9.Cu" signal "L10")
		(22 "In10.Cu" signal "L11GND")
		(24 "In11.Cu" signal "L12")
		(26 "In12.Cu" signal "L13GND")
		(2 "B.Cu" signal "BOTTOM")
		(9 "F.Adhes" user "F.Adhesive")
		(11 "B.Adhes" user "B.Adhesive")
		(13 "F.Paste" user "Package Geometry/Pastemask Top")
		(15 "B.Paste" user "Package Geometry/Pastemask Bottom")
		(5 "F.SilkS" user "Ref Des/Silkscreen Top")
		(7 "B.SilkS" user "Ref Des/Silkscreen Bottom")
		(1 "F.Mask" user "Board Geometry/Soldermask Top")
		(3 "B.Mask" user "Board Geometry/Soldermask Bottom")
		(17 "Dwgs.User" user "User.Drawings")
		(19 "Cmts.User" user "User.Comments")
		(21 "Eco1.User" user "User.Eco1")
		(23 "Eco2.User" user "User.Eco2")
		(25 "Edge.Cuts" user "Board Geometry/Outline")
		(27 "Margin" user)
		(31 "F.CrtYd" user "Package Geometry/Place Bound Top")
		(29 "B.CrtYd" user "Package Geometry/Place Bound Bottom")
		(35 "F.Fab" user "Ref Des/Assembly Top")
		(33 "B.Fab" user "Ref Des/Assembly Bottom")
	)
	(footprint ""
		(layer "B.Cu")
		(at 394.2207 -19.812 90)
		(property "Reference" "R32W4"
			(at 0.8382 -0.67818 90)
			(unlocked yes)
			(layer "B.SilkS")
			(effects
				(font
					(size 0.4064 0.254)
					(thickness 0.1524)
				)
				(justify left mirror)
			)
		)
		(property "Value" ""
			(at 0 0 90)
			(layer "B.Fab")
			(effects
				(font
					(size 1.27 1.27)
				)
				(justify mirror)
			)
		)
		(duplicate_pad_numbers_are_jumpers no)
		(fp_poly
			(pts
				(xy 0.2794 -0.1016) (xy -0.2794 -0.1016) (xy -0.2794 0.9906) (xy 0.2794 0.9906)
			)
			(stroke
				(width 0)
				(type default)
			)
			(fill no)
			(layer "B.CrtYd")
		)
		(fp_line
			(start 0.2794 -0.1016)
			(end 0.2794 0.9906)
			(stroke
				(width 0.1)
				(type default)
			)
			(layer "B.Fab")
		)
		(fp_line
			(start -0.2794 -0.1016)
			(end 0.2794 -0.1016)
			(stroke
				(width 0.1)
				(type default)
			)
			(layer "B.Fab")
		)
		(fp_line
			(start 0.2794 0.9906)
			(end -0.2794 0.9906)
			(stroke
				(width 0.1)
				(type default)
			)
			(layer "B.Fab")
		)
		(fp_line
			(start -0.2794 0.9906)
			(end -0.2794 -0.1016)
			(stroke
				(width 0.1)
				(type default)
			)
			(layer "B.Fab")
		)
		(pad "1" smd rect
			(at 0 0 270)
			(size 0.508 0.508)
			(layers "B.Cu" "B.Mask" "B.Paste")
			(net "P1V8_M2")
		)
		(pad "2" smd rect
			(at 0 0.889 270)
			(size 0.508 0.508)
			(layers "B.Cu" "B.Mask" "B.Paste")
			(net "GND")
		)
		(zone
			(layer "B.Cu")
			(hatch none 0.5)
			(connect_pads
				(clearance 0)
			)
			(min_thickness 0.25)
			(keepout
				(tracks allowed)
				(vias not_allowed)
				(pads allowed)
				(copperpour not_allowed)
				(footprints allowed)
			)
			(placement
				(enabled no)
				(sheetname "")
			)
			(fill
				(thermal_gap 0.5)
				(thermal_bridge_width 0.5)
				(island_removal_mode 0)
			)
			(polygon
				(pts
					(xy 394.4747 -20.066) (xy 394.4747 -19.558) (xy 394.8557 -19.558) (xy 394.8557 -20.066)
				)
			)
		)
		(zone
			(layer "B.Cu")
			(hatch none 0.5)
			(connect_pads
				(clearance 0)
			)
			(min_thickness 0.25)
			(keepout
				(tracks not_allowed)
				(vias allowed)
				(pads allowed)
				(copperpour not_allowed)
				(footprints allowed)
			)
			(placement
				(enabled no)
				(sheetname "")
			)
			(fill
				(thermal_gap 0.5)
				(thermal_bridge_width 0.5)
				(island_removal_mode 0)
			)
			(polygon
				(pts
					(xy 394.8557 -20.066) (xy 394.8557 -19.558) (xy 394.4747 -19.558) (xy 394.4747 -20.066)
				)
			)
		)
	)
	(footprint ""
		(layer "B.Cu")
		(at 409.3845 -24.384 -90)
		(property "Reference" "C25W60"
			(at 0.8382 -0.67818 270)
			(unlocked yes)
			(layer "B.SilkS")
			(effects
				(font
					(size 0.4064 0.254)
					(thickness 0.1524)
				)
				(justify left mirror)
			)
		)
		(property "Value" ""
			(at 0 0 90)
			(layer "B.Fab")
			(effects
				(font
					(size 1.27 1.27)
				)
				(justify mirror)
			)
		)
		(duplicate_pad_numbers_are_jumpers no)
		(fp_poly
			(pts
				(xy -0.3048 -0.1016) (xy -0.3048 0.9906) (xy 0.3048 0.9906) (xy 0.3048 -0.1016)
			)
			(stroke
				(width 0)
				(type default)
			)
			(fill no)
			(layer "B.CrtYd")
		)
		(fp_line
			(start -0.3048 0.9906)
			(end -0.3048 -0.1016)
			(stroke
				(width 0.1)
				(type default)
			)
			(layer "B.Fab")
		)
		(fp_line
			(start 0.3048 0.9906)
			(end -0.3048 0.9906)
			(stroke
				(width 0.1)
				(type default)
			)
			(layer "B.Fab")
		)
		(fp_line
			(start -0.3048 -0.1016)
			(end 0.3048 -0.1016)
			(stroke
				(width 0.1)
				(type default)
			)
			(layer "B.Fab")
		)
		(fp_line
			(start 0.3048 -0.1016)
			(end 0.3048 0.9906)
			(stroke
				(width 0.1)
				(type default)
			)
			(layer "B.Fab")
		)
		(pad "1" smd rect
			(at 0 0 90)
			(size 0.508 0.508)
			(layers "B.Cu" "B.Mask" "B.Paste")
			(net "P3V3_STBY")
		)
		(pad "2" smd rect
			(at 0 0.889 90)
			(size 0.508 0.508)
			(layers "B.Cu" "B.Mask" "B.Paste")
			(net "GND")
		)
		(zone
			(layer "B.Cu")
			(hatch none 0.5)
			(connect_pads
				(clearance 0)
			)
			(min_thickness 0.25)
			(keepout
				(tracks not_allowed)
				(vias allowed)
				(pads allowed)
				(copperpour not_allowed)
				(footprints allowed)
			)
			(placement
				(enabled no)
				(sheetname "")
			)
			(fill
				(thermal_gap 0.5)
				(thermal_bridge_width 0.5)
				(island_removal_mode 0)
			)
			(polygon
				(pts
					(xy 408.7495 -24.13) (xy 408.7495 -24.638) (xy 409.1305 -24.638) (xy 409.1305 -24.13)
				)
			)
		)
		(zone
			(layer "B.Cu")
			(hatch none 0.5)
			(connect_pads
				(clearance 0)
			)
			(min_thickness 0.25)
			(keepout
				(tracks allowed)
				(vias not_allowed)
				(pads allowed)
				(copperpour not_allowed)
				(footprints allowed)
			)
			(placement
				(enabled no)
				(sheetname "")
			)
			(fill
				(thermal_gap 0.5)
				(thermal_bridge_width 0.5)
				(island_removal_mode 0)
			)
			(polygon
				(pts
					(xy 409.1305 -24.13) (xy 409.1305 -24.638) (xy 408.7495 -24.638) (xy 408.7495 -24.13)
				)
			)
		)
	)
	(footprint ""
		(layer "B.Cu")
		(at 452.35241 -3.852672 90)
		(property "Reference" "R1U63"
			(at 0 0 90)
			(layer "B.SilkS")
			(hide yes)
			(effects
				(font
					(size 1.27 1.27)
				)
				(justify mirror)
			)
		)
		(property "Value" ""
			(at 0 0 90)
			(layer "B.Fab")
			(effects
				(font
					(size 1.27 1.27)
				)
				(justify mirror)
			)
		)
		(duplicate_pad_numbers_are_jumpers no)
		(fp_poly
			(pts
				(xy 0.2794 -0.1016) (xy -0.2794 -0.1016) (xy -0.2794 0.9906) (xy 0.2794 0.9906)
			)
			(stroke
				(width 0)
				(type default)
			)
			(fill no)
			(layer "B.CrtYd")
		)
		(fp_line
			(start 0.2794 -0.1016)
			(end 0.2794 0.9906)
			(stroke
				(width 0.1)
				(type default)
			)
			(layer "B.Fab")
		)
		(fp_line
			(start -0.2794 -0.1016)
			(end 0.2794 -0.1016)
			(stroke
				(width 0.1)
				(type default)
			)
			(layer "B.Fab")
		)
		(fp_line
			(start 0.2794 0.9906)
			(end -0.2794 0.9906)
			(stroke
				(width 0.1)
				(type default)
			)
			(layer "B.Fab")
		)
		(fp_line
			(start -0.2794 0.9906)
			(end -0.2794 -0.1016)
			(stroke
				(width 0.1)
				(type default)
			)
			(layer "B.Fab")
		)
		(pad "1" smd rect
			(at 0 0 270)
			(size 0.508 0.508)
			(layers "B.Cu" "B.Mask" "B.Paste")
			(net "PD_RST_RTCRST_N")
		)
		(pad "2" smd rect
			(at 0 0.889 270)
			(size 0.508 0.508)
			(layers "B.Cu" "B.Mask" "B.Paste")
			(net "GND")
		)
		(zone
			(layer "B.Cu")
			(hatch none 0.5)
			(connect_pads
				(clearance 0)
			)
			(min_thickness 0.25)
			(keepout
				(tracks allowed)
				(vias not_allowed)
				(pads allowed)
				(copperpour not_allowed)
				(footprints allowed)
			)
			(placement
				(enabled no)
				(sheetname "")
			)
			(fill
				(thermal_gap 0.5)
				(thermal_bridge_width 0.5)
				(island_removal_mode 0)
			)
			(polygon
				(pts
					(xy 452.60641 -4.106672) (xy 452.60641 -3.598672) (xy 452.98741 -3.598672) (xy 452.98741 -4.106672)
				)
			)
		)
		(zone
			(layer "B.Cu")
			(hatch none 0.5)
			(connect_pads
				(clearance 0)
			)
			(min_thickness 0.25)
			(keepout
				(tracks not_allowed)
				(vias allowed)
				(pads allowed)
				(copperpour not_allowed)
				(footprints allowed)
			)
			(placement
				(enabled no)
				(sheetname "")
			)
			(fill
				(thermal_gap 0.5)
				(thermal_bridge_width 0.5)
				(island_removal_mode 0)
			)
			(polygon
				(pts
					(xy 452.98741 -4.106672) (xy 452.98741 -3.598672) (xy 452.60641 -3.598672) (xy 452.60641 -4.106672)
				)
			)
		)
	)
	(footprint ""
		(layer "B.Cu")
		(at 444.1317 -36.738052 180)
		(property "Reference" "R25W119"
			(at 0.8382 -0.67818 180)
			(unlocked yes)
			(layer "B.SilkS")
			(effects
				(font
					(size 0.4064 0.254)
					(thickness 0.1524)
				)
				(justify left mirror)
			)
		)
		(property "Value" ""
			(at 0 0 0)
			(layer "B.Fab")
			(effects
				(font
					(size 1.27 1.27)
				)
				(justify mirror)
			)
		)
		(duplicate_pad_numbers_are_jumpers no)
		(fp_poly
			(pts
				(xy 0.2794 -0.1016) (xy -0.2794 -0.1016) (xy -0.2794 0.9906) (xy 0.2794 0.9906)
			)
			(stroke
				(width 0)
				(type default)
			)
			(fill no)
			(layer "B.CrtYd")
		)
		(fp_line
			(start 0.2794 0.9906)
			(end -0.2794 0.9906)
			(stroke
				(width 0.1)
				(type default)
			)
			(layer "B.Fab")
		)
		(fp_line
			(start 0.2794 -0.1016)
			(end 0.2794 0.9906)
			(stroke
				(width 0.1)
				(type default)
			)
			(layer "B.Fab")
		)
		(fp_line
			(start -0.2794 0.9906)
			(end -0.2794 -0.1016)
			(stroke
				(width 0.1)
				(type default)
			)
			(layer "B.Fab")
		)
		(fp_line
			(start -0.2794 -0.1016)
			(end 0.2794 -0.1016)
			(stroke
				(width 0.1)
				(type default)
			)
			(layer "B.Fab")
		)
		(pad "1" smd rect
			(at 0 0)
			(size 0.508 0.508)
			(layers "B.Cu" "B.Mask" "B.Paste")
			(net "P1V2_AUX_BMC")
		)
		(pad "2" smd rect
			(at 0 0.889)
			(size 0.508 0.508)
			(layers "B.Cu" "B.Mask" "B.Paste")
			(net "BMC_M_PAR")
		)
		(zone
			(layer "B.Cu")
			(hatch none 0.5)
			(connect_pads
				(clearance 0)
			)
			(min_thickness 0.25)
			(keepout
				(tracks not_allowed)
				(vias allowed)
				(pads allowed)
				(copperpour not_allowed)
				(footprints allowed)
			)
			(placement
				(enabled no)
				(sheetname "")
			)
			(fill
				(thermal_gap 0.5)
				(thermal_bridge_width 0.5)
				(island_removal_mode 0)
			)
			(polygon
				(pts
					(xy 443.8777 -37.373052) (xy 444.3857 -37.373052) (xy 444.3857 -36.992052) (xy 443.8777 -36.992052)
				)
			)
		)
		(zone
			(layer "B.Cu")
			(hatch none 0.5)
			(connect_pads
				(clearance 0)
			)
			(min_thickness 0.25)
			(keepout
				(tracks allowed)
				(vias not_allowed)
				(pads allowed)
				(copperpour not_allowed)
				(footprints allowed)
			)
			(placement
				(enabled no)
				(sheetname "")
			)
			(fill
				(thermal_gap 0.5)
				(thermal_bridge_width 0.5)
				(island_removal_mode 0)
			)
			(polygon
				(pts
					(xy 443.8777 -36.992052) (xy 444.3857 -36.992052) (xy 444.3857 -37.373052) (xy 443.8777 -37.373052)
				)
			)
		)
	)
	(footprint ""
		(layer "B.Cu")
		(at 452.5772 -149.0345 180)
		(property "Reference" "R25W183"
			(at 0 0 0)
			(layer "B.SilkS")
			(hide yes)
			(effects
				(font
					(size 1.27 1.27)
				)
				(justify mirror)
			)
		)
		(property "Value" "*"
			(at -0.064008 -4.108196 180)
			(unlocked yes)
			(layer "B.Fab")
			(hide yes)
			(effects
				(font
					(size 1.27 1.016)
					(thickness 0.1524)
				)
				(justify mirror)
			)
		)
		(property "Device Type" "374R2F-1-GP_SMD-RG-374R2F-1-GPA"
			(at -0.064008 -5.632196 180)
			(unlocked yes)
			(layer "B.Fab")
			(hide yes)
			(effects
				(font
					(size 1.27 1.016)
					(thickness 0.1524)
				)
				(justify mirror)
			)
		)
		(duplicate_pad_numbers_are_jumpers no)
		(fp_line
			(start 0.508 -0.9398)
			(end 0.508 0.9398)
			(stroke
				(width 0.1524)
				(type default)
			)
			(layer "B.SilkS")
		)
		(fp_line
			(start -0.508 -0.9398)
			(end 0.508 -0.9398)
			(stroke
				(width 0.1524)
				(type default)
			)
			(layer "B.SilkS")
		)
		(fp_rect
			(start 0.508 0.9398)
			(end -0.508 -0.9398)
			(stroke
				(width 0)
				(type default)
			)
			(fill no)
			(layer "B.CrtYd")
		)
		(fp_rect
			(start 0.508 0.9398)
			(end -0.508 -0.9398)
			(stroke
				(width 0)
				(type default)
			)
			(fill no)
			(layer "B.Fab")
		)
		(pad "1" smd custom
			(at 0 -0.4445)
			(size 0.1397 0.1397)
			(layers "B.Cu" "B.Mask" "B.Paste")
			(net "P3V3_STBY")
			(options
				(clearance outline)
				(anchor circle)
			)
			(primitives
				(gr_poly
					(pts
						(arc
							(start -0.1778 0.2794)
							(mid -0.249642 0.249642)
							(end -0.2794 0.1778)
						)
						(arc
							(start -0.2794 -0.1778)
							(mid -0.249642 -0.249642)
							(end -0.1778 -0.2794)
						)
						(arc
							(start 0.1778 -0.2794)
							(mid 0.249642 -0.249642)
							(end 0.2794 -0.1778)
						)
						(arc
							(start 0.2794 0.1778)
							(mid 0.249642 0.249642)
							(end 0.1778 0.2794)
						)
					)
					(width 0)
					(fill yes)
				)
			)
		)
		(pad "2" smd custom
			(at 0 0.4445)
			(size 0.1397 0.1397)
			(layers "B.Cu" "B.Mask" "B.Paste")
			(net "P0V7_GTL2014_VREF_6")
			(options
				(clearance outline)
				(anchor circle)
			)
			(primitives
				(gr_poly
					(pts
						(arc
							(start -0.1778 0.2794)
							(mid -0.249642 0.249642)
							(end -0.2794 0.1778)
						)
						(arc
							(start -0.2794 -0.1778)
							(mid -0.249642 -0.249642)
							(end -0.1778 -0.2794)
						)
						(arc
							(start 0.1778 -0.2794)
							(mid 0.249642 -0.249642)
							(end 0.2794 -0.1778)
						)
						(arc
							(start 0.2794 0.1778)
							(mid 0.249642 0.249642)
							(end 0.1778 0.2794)
						)
					)
					(width 0)
					(fill yes)
				)
			)
		)
	)
	(footprint ""
		(layer "B.Cu")
		(at 385.318 -87.1601 180)
		(property "Reference" "R3P61"
			(at 0 0 0)
			(layer "B.SilkS")
			(hide yes)
			(effects
				(font
					(size 1.27 1.27)
				)
				(justify mirror)
			)
		)
		(property "Value" ""
			(at 0 0 0)
			(layer "B.Fab")
			(effects
				(font
					(size 1.27 1.27)
				)
				(justify mirror)
			)
		)
		(duplicate_pad_numbers_are_jumpers no)
		(fp_poly
			(pts
				(xy 0.2794 -0.1016) (xy -0.2794 -0.1016) (xy -0.2794 0.9906) (xy 0.2794 0.9906)
			)
			(stroke
				(width 0)
				(type default)
			)
			(fill no)
			(layer "B.CrtYd")
		)
		(fp_line
			(start 0.2794 0.9906)
			(end -0.2794 0.9906)
			(stroke
				(width 0.1)
				(type default)
			)
			(layer "B.Fab")
		)
		(fp_line
			(start 0.2794 -0.1016)
			(end 0.2794 0.9906)
			(stroke
				(width 0.1)
				(type default)
			)
			(layer "B.Fab")
		)
		(fp_line
			(start -0.2794 0.9906)
			(end -0.2794 -0.1016)
			(stroke
				(width 0.1)
				(type default)
			)
			(layer "B.Fab")
		)
		(fp_line
			(start -0.2794 -0.1016)
			(end 0.2794 -0.1016)
			(stroke
				(width 0.1)
				(type default)
			)
			(layer "B.Fab")
		)
		(pad "1" smd rect
			(at 0 0)
			(size 0.508 0.508)
			(layers "B.Cu" "B.Mask" "B.Paste")
			(net "P3V3_STBY")
		)
		(pad "2" smd rect
			(at 0 0.889)
			(size 0.508 0.508)
			(layers "B.Cu" "B.Mask" "B.Paste")
			(net "FM_MB_SLOT_ID2")
		)
		(zone
			(layer "B.Cu")
			(hatch none 0.5)
			(connect_pads
				(clearance 0)
			)
			(min_thickness 0.25)
			(keepout
				(tracks not_allowed)
				(vias allowed)
				(pads allowed)
				(copperpour not_allowed)
				(footprints allowed)
			)
			(placement
				(enabled no)
				(sheetname "")
			)
			(fill
				(thermal_gap 0.5)
				(thermal_bridge_width 0.5)
				(island_removal_mode 0)
			)
			(polygon
				(pts
					(xy 385.064 -87.7951) (xy 385.572 -87.7951) (xy 385.572 -87.4141) (xy 385.064 -87.4141)
				)
			)
		)
		(zone
			(layer "B.Cu")
			(hatch none 0.5)
			(connect_pads
				(clearance 0)
			)
			(min_thickness 0.25)
			(keepout
				(tracks allowed)
				(vias not_allowed)
				(pads allowed)
				(copperpour not_allowed)
				(footprints allowed)
			)
			(placement
				(enabled no)
				(sheetname "")
			)
			(fill
				(thermal_gap 0.5)
				(thermal_bridge_width 0.5)
				(island_removal_mode 0)
			)
			(polygon
				(pts
					(xy 385.064 -87.4141) (xy 385.572 -87.4141) (xy 385.572 -87.7951) (xy 385.064 -87.7951)
				)
			)
		)
	)
	(footprint ""
		(layer "B.Cu")
		(at 428.3075 -22.606 -90)
		(property "Reference" "R25W130"
			(at 0.8382 -0.67818 270)
			(unlocked yes)
			(layer "B.SilkS")
			(effects
				(font
					(size 0.4064 0.254)
					(thickness 0.1524)
				)
				(justify left mirror)
			)
		)
		(property "Value" ""
			(at 0 0 90)
			(layer "B.Fab")
			(effects
				(font
					(size 1.27 1.27)
				)
				(justify mirror)
			)
		)
		(duplicate_pad_numbers_are_jumpers no)
		(fp_poly
			(pts
				(xy 0.2794 -0.1016) (xy -0.2794 -0.1016) (xy -0.2794 0.9906) (xy 0.2794 0.9906)
			)
			(stroke
				(width 0)
				(type default)
			)
			(fill no)
			(layer "B.CrtYd")
		)
		(fp_line
			(start -0.2794 0.9906)
			(end -0.2794 -0.1016)
			(stroke
				(width 0.1)
				(type default)
			)
			(layer "B.Fab")
		)
		(fp_line
			(start 0.2794 0.9906)
			(end -0.2794 0.9906)
			(stroke
				(width 0.1)
				(type default)
			)
			(layer "B.Fab")
		)
		(fp_line
			(start -0.2794 -0.1016)
			(end 0.2794 -0.1016)
			(stroke
				(width 0.1)
				(type default)
			)
			(layer "B.Fab")
		)
		(fp_line
			(start 0.2794 -0.1016)
			(end 0.2794 0.9906)
			(stroke
				(width 0.1)
				(type default)
			)
			(layer "B.Fab")
		)
		(pad "1" smd rect
			(at 0 0 90)
			(size 0.508 0.508)
			(layers "B.Cu" "B.Mask" "B.Paste")
			(net "P3V3")
		)
		(pad "2" smd rect
			(at 0 0.889 90)
			(size 0.508 0.508)
			(layers "B.Cu" "B.Mask" "B.Paste")
			(net "I2C_BMC_VGA_DDC_SDA")
		)
		(zone
			(layer "B.Cu")
			(hatch none 0.5)
			(connect_pads
				(clearance 0)
			)
			(min_thickness 0.25)
			(keepout
				(tracks not_allowed)
				(vias allowed)
				(pads allowed)
				(copperpour not_allowed)
				(footprints allowed)
			)
			(placement
				(enabled no)
				(sheetname "")
			)
			(fill
				(thermal_gap 0.5)
				(thermal_bridge_width 0.5)
				(island_removal_mode 0)
			)
			(polygon
				(pts
					(xy 427.6725 -22.352) (xy 427.6725 -22.86) (xy 428.0535 -22.86) (xy 428.0535 -22.352)
				)
			)
		)
		(zone
			(layer "B.Cu")
			(hatch none 0.5)
			(connect_pads
				(clearance 0)
			)
			(min_thickness 0.25)
			(keepout
				(tracks allowed)
				(vias not_allowed)
				(pads allowed)
				(copperpour not_allowed)
				(footprints allowed)
			)
			(placement
				(enabled no)
				(sheetname "")
			)
			(fill
				(thermal_gap 0.5)
				(thermal_bridge_width 0.5)
				(island_removal_mode 0)
			)
			(polygon
				(pts
					(xy 428.0535 -22.352) (xy 428.0535 -22.86) (xy 427.6725 -22.86) (xy 427.6725 -22.352)
				)
			)
		)
	)
)
